# S9S_MB_2U (Grand Teton) — schematic netlist excerpt (pin names and nets, part order shuffled) for the footprints in the layout excerpt that follows; sources: Cadence DE-HDL packaged netlist, KiCad conversion of 03242023_DA0F0TMBIJ0_F0T_Motherboard_J_brd_V01_OCP.brd

PC316  Q_CAPP  560UF 2.5V 20% OSCON  pkg THLF  page 267 : A = PVCCIN_CPU0 ; B = GND
R1756  Q_RES  33.2 1% CHIP  pkg 0402LF  page 222 : A = SGPIO_CLK_1 ; B = SGPIO_BMC_CLK

(kicad_pcb
	(version 20260206)
	(generator "pcbnew")
	(generator_version "10.0")
	(general
		(thickness 1.6)
		(legacy_teardrops no)
	)
	(paper "A4")
	(title_block
		(title "03242023_DA0F0TMBIJ0_F0T_Motherboard_J_brd_V01_OCP.brd")
		(comment 1 "Grand Teton / footprints 3898-3899 of 6105")
	)
	(layers
		(0 "F.Cu" signal "TOP")
		(4 "In1.Cu" signal "GND")
		(6 "In2.Cu" signal "IN1")
		(8 "In3.Cu" signal "GND1")
		(10 "In4.Cu" signal "IN2")
		(12 "In5.Cu" signal "GND2")
		(14 "In6.Cu" signal "IN3")
		(16 "In7.Cu" signal "GND3")
		(18 "In8.Cu" signal "VCC")
		(20 "In9.Cu" signal "VCC1")
		(22 "In10.Cu" signal "GND4")
		(24 "In11.Cu" signal "IN4")
		(26 "In12.Cu" signal "GND5")
		(28 "In13.Cu" signal "IN5")
		(30 "In14.Cu" signal "GND6")
		(32 "In15.Cu" signal "IN6")
		(34 "In16.Cu" signal "GND7")
		(2 "B.Cu" signal "BOTTOM")
		(9 "F.Adhes" user "F.Adhesive")
		(11 "B.Adhes" user "B.Adhesive")
		(13 "F.Paste" user "Package Geometry/Pastemask Top")
		(15 "B.Paste" user "Package Geometry/Pastemask Bottom")
		(5 "F.SilkS" user "Ref Des/Silkscreen Top")
		(7 "B.SilkS" user "Ref Des/Silkscreen Bottom")
		(1 "F.Mask" user "Board Geometry/Soldermask Top")
		(3 "B.Mask" user "Board Geometry/Soldermask Bottom")
		(17 "Dwgs.User" user "User.Drawings")
		(19 "Cmts.User" user "User.Comments")
		(21 "Eco1.User" user "User.Eco1")
		(23 "Eco2.User" user "User.Eco2")
		(25 "Edge.Cuts" user "Board Geometry/Outline")
		(27 "Margin" user)
		(31 "F.CrtYd" user "Package Geometry/Place Bound Top")
		(29 "B.CrtYd" user "Package Geometry/Place Bound Bottom")
		(35 "F.Fab" user "Ref Des/Assembly Top")
		(33 "B.Fab" user "Ref Des/Assembly Bottom")
	)
	(footprint ""
		(layer "F.Cu")
		(at 164.592 -102.199948)
		(property "Reference" "R1756"
			(at 0 0 0)
			(layer "F.SilkS")
			(hide yes)
			(effects
				(font
					(size 1.27 1.27)
				)
			)
		)
		(property "Value" ""
			(at 0 0 0)
			(layer "F.Fab")
			(effects
				(font
					(size 1.27 1.27)
				)
			)
		)
		(duplicate_pad_numbers_are_jumpers no)
		(fp_line
			(start -0.7874 -0.4064)
			(end 0.7874 -0.4064)
			(stroke
				(width 0.1524)
				(type default)
			)
			(layer "F.SilkS")
		)
		(fp_line
			(start -0.7874 0.4064)
			(end -0.7874 -0.4064)
			(stroke
				(width 0.1524)
				(type default)
			)
			(layer "F.SilkS")
		)
		(fp_line
			(start 0.7874 -0.4064)
			(end 0.7874 0.4064)
			(stroke
				(width 0.1524)
				(type default)
			)
			(layer "F.SilkS")
		)
		(fp_line
			(start 0.7874 0.4064)
			(end -0.7874 0.4064)
			(stroke
				(width 0.1524)
				(type default)
			)
			(layer "F.SilkS")
		)
		(fp_line
			(start -0.67945 -0.305054)
			(end -0.12065 -0.305054)
			(stroke
				(width 0.1)
				(type default)
			)
			(layer "F.Fab")
		)
		(fp_line
			(start -0.67945 0.3048)
			(end -0.67945 -0.305054)
			(stroke
				(width 0.1)
				(type default)
			)
			(layer "F.Fab")
		)
		(fp_line
			(start -0.12065 -0.305054)
			(end -0.12065 -0.2794)
			(stroke
				(width 0.1)
				(type default)
			)
			(layer "F.Fab")
		)
		(fp_line
			(start -0.12065 -0.2794)
			(end 0.12065 -0.2794)
			(stroke
				(width 0.1)
				(type default)
			)
			(layer "F.Fab")
		)
		(fp_line
			(start -0.12065 0.2794)
			(end -0.12065 0.3048)
			(stroke
				(width 0.1)
				(type default)
			)
			(layer "F.Fab")
		)
		(fp_line
			(start -0.12065 0.3048)
			(end -0.67945 0.3048)
			(stroke
				(width 0.1)
				(type default)
			)
			(layer "F.Fab")
		)
		(fp_line
			(start 0.120396 0.2794)
			(end -0.12065 0.2794)
			(stroke
				(width 0.1)
				(type default)
			)
			(layer "F.Fab")
		)
		(fp_line
			(start 0.120396 0.3048)
			(end 0.120396 0.2794)
			(stroke
				(width 0.1)
				(type default)
			)
			(layer "F.Fab")
		)
		(fp_line
			(start 0.12065 -0.3048)
			(end 0.67945 -0.3048)
			(stroke
				(width 0.1)
				(type default)
			)
			(layer "F.Fab")
		)
		(fp_line
			(start 0.12065 -0.2794)
			(end 0.12065 -0.3048)
			(stroke
				(width 0.1)
				(type default)
			)
			(layer "F.Fab")
		)
		(fp_line
			(start 0.67945 -0.3048)
			(end 0.67945 0.3048)
			(stroke
				(width 0.1)
				(type default)
			)
			(layer "F.Fab")
		)
		(fp_line
			(start 0.67945 0.3048)
			(end 0.120396 0.3048)
			(stroke
				(width 0.1)
				(type default)
			)
			(layer "F.Fab")
		)
		(pad "1" smd circle
			(at -0.40005 0)
			(size 0 0)
			(layers "F.Cu" "F.Mask" "F.Paste")
			(net "SGPIO_CLK_1")
		)
		(pad "2" smd circle
			(at 0.40005 0)
			(size 0 0)
			(layers "F.Cu" "F.Mask" "F.Paste")
			(net "SGPIO_BMC_CLK")
		)
	)
	(footprint ""
		(layer "F.Cu")
		(at 365.03864 -315.66739 90)
		(property "Reference" "PC316"
			(at 0 0 90)
			(layer "F.SilkS")
			(hide yes)
			(effects
				(font
					(size 1.27 1.27)
				)
			)
		)
		(property "Value" ""
			(at 0 0 90)
			(layer "F.Fab")
			(effects
				(font
					(size 1.27 1.27)
				)
			)
		)
		(duplicate_pad_numbers_are_jumpers no)
		(fp_line
			(start 2.750058 0.999998)
			(end -2.750058 0.999998)
			(stroke
				(width 0.1524)
				(type default)
			)
			(layer "F.SilkS")
		)
		(fp_circle
			(center 0 0.999998)
			(end 0 3.750056)
			(stroke
				(width 0.1524)
				(type default)
			)
			(fill no)
			(layer "F.SilkS")
		)
		(fp_poly
			(pts
				(arc
					(start 2.750058 0.999998)
					(mid 0 3.750056)
					(end -2.750058 0.999998)
				)
			)
			(stroke
				(width 0)
				(type default)
			)
			(fill yes)
			(layer "F.SilkS")
		)
		(fp_circle
			(center 0 0.999998)
			(end 0 3.750056)
			(stroke
				(width 0.1)
				(type default)
			)
			(fill no)
			(layer "F.Fab")
		)
		(pad "1" thru_hole rect
			(at 0 0 90)
			(size 1.5748 1.5748)
			(drill 1.0668)
			(layers "*.Cu" "*.Mask")
			(remove_unused_layers no)
			(net "PVCCIN_CPU0")
			(clearance 0)
			(padstack
				(mode front_inner_back)
				(layer "Inner"
					(shape circle)
					(size 1.5748 1.5748)
					(clearance 0)
				)
				(layer "B.Cu"
					(shape rect)
					(size 1.5748 1.5748)
					(clearance 0)
				)
			)
		)
		(pad "2" thru_hole circle
			(at 0 1.999996 90)
			(size 1.5748 1.5748)
			(drill 1.0668)
			(layers "*.Cu" "*.Mask")
			(remove_unused_layers no)
			(net "GND")
			(clearance 0)
		)
	)
)
